FILE_TYPE = MULTI_PHYS_TABLE;
PART 'CAPP'
{========================================================================================}
:VALUE     | VOLTAGE | TOLERANCE  | PACK_TYPE  | MATERIAL | PART_NUMBER     = ENVCOMP                            | PART_NUMBER   | JEDEC_TYPE       | VALUE     | RATED_VOLTAGE | TOL        | CLASS      | DESCRIPTION                                                  | HEIGHT     | COMPONENT_TYPE | LEAD_LENGTH | LPID   | SPEED_URL                                                                                                                        | STATUS        | RPL   | AML  | BUS_UNIT      | DAYS  ;
{========================================================================================}
'270uF'   | '16V'   | '20%'      | '2626'     | 'OSCON'  | 'A31228-047'(!) = 'YES;YES;YES;UNK;ok;VLD'           | 'A31228-047'  | 'SMC2626_ALEL_C' | '270uF'   | '16V'         | '20%'      | 'DISCRETE' | 'CAPA,270.00UF,6.3X9.9,16.00V,SM'                            | '0.394 IN' | 'SMTOTHER'     | ''          | '1792' | 'http://speed.intel.com:8081/speed/module/pdm/item/pdm_item_detail_direct.asp?item_cde=A31228-047&item_rev=01&url_param=unused'  | 'Design'      | 'YES' | '1'  | 'SMO_BOARDS'  | '???'
'270uF'   | '16V'   | '20%'      | '2626'     | 'EMPTY'  | 'A31228-047'(!) = 'YES;YES;YES;UNK;ok;VLD'           | 'A31228-047'  | 'SMC2626_ALEL_C' | 'NA'      | '16V'         | '20%'      | 'DISCRETE' | 'CAPA,270.00UF,6.3X9.9,16.00V,SM'                            | '0.394 IN' | 'SMTOTHER'     | ''          | '1792' | 'http://speed.intel.com:8081/speed/module/pdm/item/pdm_item_detail_direct.asp?item_cde=A31228-047&item_rev=01&url_param=unused'  | 'Design'      | 'YES' | '1'  | 'SMO_BOARDS'  | '???'
'470uF'   | '2V'    | '20%'      | 'SM'       | 'ALUM'   | '699013-031'(!) = 'YES;YES;YES;UNK;ok;VLD'           | '699013-031'  | 'SMC3018B'       | '470uF'   | '2V'          | '20%'      | 'DISCRETE' | '470uF POLARIZED CAP'                                        | '0.083 IN' | 'SMTOTHER'     | ''          | '481'  | 'http://speed.intel.com:8081/speed/module/pdm/item/pdm_item_detail_direct.asp?item_cde=699013-031&item_rev=01&url_param=unused'  | 'Conditional' | 'NO'  | '1'  | 'SMO_BOARDS'  | '42' 
'470uF'   | '2V'    | '20%'      | 'SM'       | 'EMPTY'  | '699013-031'(!) = 'YES;YES;YES;UNK;ok;VLD'           | '699013-031'  | 'SMC3018B'       | 'NA'      | '2V'          | '20%'      | 'DISCRETE' | '470uF POLARIZED CAP'                                        | '0.083 IN' | 'SMTOTHER'     | ''          | '481'  | 'http://speed.intel.com:8081/speed/module/pdm/item/pdm_item_detail_direct.asp?item_cde=699013-031&item_rev=01&url_param=unused'  | 'Conditional' | 'NO'  | '1'  | 'SMO_BOARDS'  | '42' 
'470uF'   | '2.5V'  | '20%'      | '3018'     | 'ALUM'   | '699013-049'(!) = 'YES;YES;YES;UNK;ok;VLD'           | '699013-049'  | 'SMC3018B'       | '470uF'   | '2.5V'        | '20%'      | 'DISCRETE' | 'CAPS,TA-P,D4,470.00uF,2.5V,+/- 20%'                         | '0.079 IN' | 'SMTOTHER'     | ''          | '481'  | 'http://speed.intel.com:8081/speed/module/pdm/item/pdm_item_detail_direct.asp?item_cde=699013-049&item_rev=01&url_param=unused'  | 'Design'      | 'N/A' | '1'  | 'SMO_BOARDS'  | '56' 
'470uF'   | '2.5V'  | '20%'      | '3018'     | 'EMPTY'  | '699013-049'(!) = 'YES;YES;YES;UNK;ok;VLD'           | '699013-049'  | 'SMC3018B'       | 'NA'      | '2.5V'        | '20%'      | 'DISCRETE' | 'CAPS,TA-P,D4,470.00uF,2.5V,+/- 20%'                         | '0.079 IN' | 'SMTOTHER'     | ''          | '481'  | 'http://speed.intel.com:8081/speed/module/pdm/item/pdm_item_detail_direct.asp?item_cde=699013-049&item_rev=01&url_param=unused'  | 'Design'      | 'N/A' | '1'  | 'SMO_BOARDS'  | '56' 
'470uF'   | '6.3V'  | '20%'      | '3018'     | 'TANT'   | '724613-091'(!) = 'YES;YES;YES;UNK;ok;VLD'           | '724613-091'  | 'SMC3018B'       | '470uF'   | '6.3V'        | '20%'      | 'DISCRETE' | 'CAPS,TA-P,V,470uF,6.3V,20%'                                 | '0.158 IN' | 'SMTOTHER'     | ''          | '481'  | 'http://speed.intel.com:8081/speed/module/pdm/item/pdm_item_detail_direct.asp?item_cde=724613-091&item_rev=01&url_param=unused'  | 'Unqual'      | 'YES' | '2'  | 'SMO_BOARDS'  | '???'
'470uF'   | '6.3V'  | '20%'      | '3018'     | 'POSCAP' | '724613-091'(!) = 'YES;YES;YES;UNK;ok;VLD'           | '724613-091'  | 'SMC3018B'       | '470uF'   | '6.3V'        | '20%'      | 'DISCRETE' | 'CAPS,TA-P,V,470uF,6.3V,20%'                                 | '0.158 IN' | 'SMTOTHER'     | ''          | '481'  | 'http://speed.intel.com:8081/speed/module/pdm/item/pdm_item_detail_direct.asp?item_cde=724613-091&item_rev=01&url_param=unused'  | 'Unqual'      | 'YES' | '2'  | 'SMO_BOARDS'  | '???'
'470uF'   | '6.3V'  | '20%'      | '3018'     | 'EMPTY'  | '724613-091'(!) = 'YES;YES;YES;UNK;ok;VLD'           | '724613-091'  | 'SMC3018B'       | 'NA'      | '6.3V'        | '20%'      | 'DISCRETE' | 'CAPS,TA-P,V,470uF,6.3V,20%'                                 | '0.158 IN' | 'SMTOTHER'     | ''          | '481'  | 'http://speed.intel.com:8081/speed/module/pdm/item/pdm_item_detail_direct.asp?item_cde=724613-091&item_rev=01&url_param=unused'  | 'Unqual'      | 'YES' | '2'  | 'SMO_BOARDS'  | '???'
'68uF'    | '16V'   | '20%'      | '3018'     | 'POSCAP' | '724613-112'(!) = 'YES;YES;YES;UNK;ok;VLD'           | '724613-112'  | 'SMC3018B'       | '68uF'    | '16V'         | '20%'      | 'DISCRETE' | '68uF POLARIZED CAP'                                         | '0.079 IN' | 'SMTOTHER'     | ''          | '481'  | 'http://speed.intel.com:8081/speed/module/pdm/item/pdm_item_detail_direct.asp?item_cde=724613-112&item_rev=01&url_param=unused'  | 'Unqual'      | 'N/A' | '2'  | 'SMO_BOARDS'  | '112'
'68uF'    | '16V'   | '20%'      | '3018'     | 'EMPTY'  | '724613-112'(!) = 'YES;YES;YES;UNK;ok;VLD'           | '724613-112'  | 'SMC3018B'       | 'NA'      | '16V'         | '20%'      | 'DISCRETE' | '68uF POLARIZED CAP'                                         | '0.079 IN' | 'SMTOTHER'     | ''          | '481'  | 'http://speed.intel.com:8081/speed/module/pdm/item/pdm_item_detail_direct.asp?item_cde=724613-112&item_rev=01&url_param=unused'  | 'Unqual'      | 'N/A' | '2'  | 'SMO_BOARDS'  | '112'
'68uF'    | '16V'   | '20%'      | '3018'     | 'TANT'   | '724613-112'(!) = 'YES;YES;YES;UNK;ok;VLD'           | '724613-112'  | 'SMC3018B'       | '68uF'    | '16V'         | '20%'      | 'DISCRETE' | '68uF POLARIZED CAP'                                         | '0.079 IN' | 'SMTOTHER'     | ''          | '481'  | 'http://speed.intel.com:8081/speed/module/pdm/item/pdm_item_detail_direct.asp?item_cde=724613-112&item_rev=01&url_param=unused'  | 'Unqual'      | 'N/A' | '2'  | 'SMO_BOARDS'  | '112'
'470uF'   | '16V'   | '20%'      | '4040LF'   | 'ALUM'   | 'A93539-036'(!) = 'YES;YES;UNK;UNK;ok;CIP'           | 'A93539-036'  | 'SMC4040_ALEL_B' | '470uF'   | '16V'         | '20%'      | 'DISCRETE' | '470uF POLARIZED CAP'                                        | '0.394 IN' | 'SMTOTHER'     | ''          | '494'  | 'http://speed.intel.com:8081/speed/module/pdm/item/pdm_item_detail_direct.asp?item_cde=A93539-036&item_rev=01&url_param=unused'  | 'Approved'    | 'YES' | '8'  | 'SMO_BOARDS'  | '84' 
'470uF'   | '16V'   | '20%'      | '4040LF'   | 'EMPTY'  | 'A93539-036'(!) = 'YES;YES;UNK;UNK;ok;CIP'           | 'A93539-036'  | 'SMC4040_ALEL_B' | 'NA'      | '16V'         | '20%'      | 'DISCRETE' | '470uF POLARIZED CAP'                                        | '0.394 IN' | 'SMTOTHER'     | ''          | '494'  | 'http://speed.intel.com:8081/speed/module/pdm/item/pdm_item_detail_direct.asp?item_cde=A93539-036&item_rev=01&url_param=unused'  | 'Approved'    | 'YES' | '8'  | 'SMO_BOARDS'  | '84' 
'330uF'   | '6.3V'  | '20%'      | '7343LF'   | 'TANT'   | '724613-042'(!) = 'YES;YES;YES;UNK;ok;VLD'           | '724613-042'  | 'SMC7343B'       | '330uF'   | '6.3V'        | '20%'      | 'DISCRETE' | '330uF POLARIZED CAP'                                        | '0.150 IN' | 'SMTOTHER'     | ''          | '481'  | 'http://speed.intel.com:8081/speed/module/pdm/item/pdm_item_detail_direct.asp?item_cde=724613-042&item_rev=01&url_param=unused'  | 'Conditional' | 'YES' | '4'  | 'SMO_BOARDS'  | '56' 
'330uF'   | '6.3V'  | '20%'      | '7343LF'   | 'POSCAP' | '724613-042'(!) = 'YES;YES;YES;UNK;ok;VLD'           | '724613-042'  | 'SMC7343B'       | '330uF'   | '6.3V'        | '20%'      | 'DISCRETE' | '330uF POLARIZED CAP'                                        | '0.150 IN' | 'SMTOTHER'     | ''          | '481'  | 'http://speed.intel.com:8081/speed/module/pdm/item/pdm_item_detail_direct.asp?item_cde=724613-042&item_rev=01&url_param=unused'  | 'Conditional' | 'YES' | '4'  | 'SMO_BOARDS'  | '56' 
'330uF'   | '6.3V'  | '20%'      | '7343LF'   | 'EMPTY'  | '724613-042'(!) = 'YES;YES;YES;UNK;ok;VLD'           | '724613-042'  | 'SMC7343B'       | 'NA'      | '6.3V'        | '20%'      | 'DISCRETE' | '330uF POLARIZED CAP'                                        | '0.150 IN' | 'SMTOTHER'     | ''          | '481'  | 'http://speed.intel.com:8081/speed/module/pdm/item/pdm_item_detail_direct.asp?item_cde=724613-042&item_rev=01&url_param=unused'  | 'Conditional' | 'YES' | '4'  | 'SMO_BOARDS'  | '56' 
'220uF'   | '4V'    | '20%'      | '7343'     | 'POSCAP' | '724613-067'(!) = ''                                 | '724613-067'  | 'SMC7343B'       | '220uF'   | '4V'          | '20%'      | 'DISCRETE' | 'CAPS,TA-P,V,220.000 uF,4.000V,+/- 20%'                      | '0.075 IN' | 'SMTOTHER'     | ''          | '481'  | 'http://speed.intel.com:8081/speed/module/pdm/item/pdm_item_detail_direct.asp?item_cde=724613-067&item_rev=01&url_param=unused'  | ''            | ''    | ''   | ''            | ''   
'220uF'   | '4V'    | '20%'      | '7343'     | 'EMPTY'  | '724613-067'(!) = ''                                 | '724613-067'  | 'SMC7343B'       | 'NA'      | '4V'          | '20%'      | 'DISCRETE' | 'CAPS,TA-P,V,220.000 uF,4.000V,+/- 20%'                      | '0.075 IN' | 'SMTOTHER'     | ''          | '481'  | 'http://speed.intel.com:8081/speed/module/pdm/item/pdm_item_detail_direct.asp?item_cde=724613-067&item_rev=01&url_param=unused'  | ''            | ''    | ''   | ''            | ''   
'330uF'   | '10V'   | '20%'      | '7343HLF'  | 'POSCAP' | '724613-043'(!) = 'YES;YES;YES;UNK;ok;VLD'           | '724613-043'  | 'SMC7343HB'      | '330uF'   | '10V'         | '20%'      | 'DISCRETE' | '330uF POLARIZED CAP'                                        | '0.157 IN' | 'SMTOTHER'     | ''          | '481'  | 'http://speed.intel.com:8081/speed/module/pdm/item/pdm_item_detail_direct.asp?item_cde=724613-043&item_rev=01&url_param=unused'  | 'Conditional' | 'YES' | '2'  | 'SMO_BOARDS'  | '70' 
'330uF'   | '10V'   | '20%'      | '7343HLF'  | 'EMPTY'  | '724613-043'(!) = 'YES;YES;YES;UNK;ok;VLD'           | '724613-043'  | 'SMC7343HB'      | 'NA'      | '10V'         | '20%'      | 'DISCRETE' | '330uF POLARIZED CAP'                                        | '0.157 IN' | 'SMTOTHER'     | ''          | '481'  | 'http://speed.intel.com:8081/speed/module/pdm/item/pdm_item_detail_direct.asp?item_cde=724613-043&item_rev=01&url_param=unused'  | 'Conditional' | 'YES' | '2'  | 'SMO_BOARDS'  | '70' 
END_PART
END.
